# T6G (Grand Teton) — schematic netlist excerpt (pin names and nets, part order shuffled) for the footprints in the layout excerpt that follows; sources: Cadence DE-HDL packaged netlist, KiCad conversion of 04192023_DAF0TMB3IC0_F0TG_MB_C_brd_V02_OCP.brd

PC2181  Q_CAP  1UF 25V 10% X6S  pkg C0402  page 263 : A = HSC_VDD_R_2 ; B = AGND_HSC
R1412  Q_RES  4.7K 5% CHIP  pkg 0201LF  page 309 : A = CLKREQ_RT_CPU0_P3_N ; B = GND
R3192  Q_RES  4.7K 1% EMPTY  pkg 0402LF  page 139 : A = P3V3_AUX ; B = IRQ_LVC3_V3_2_WAKE_BUF_N

(kicad_pcb
	(version 20260206)
	(generator "pcbnew")
	(generator_version "10.0")
	(general
		(thickness 1.6)
		(legacy_teardrops no)
	)
	(paper "A4")
	(title_block
		(title "04192023_DAF0TMB3IC0_F0TG_MB_C_brd_V02_OCP.brd")
		(comment 1 "Grand Teton / footprints 1162-1164 of 8354")
	)
	(layers
		(0 "F.Cu" signal "TOP")
		(4 "In1.Cu" signal "GND")
		(6 "In2.Cu" signal "IN1")
		(8 "In3.Cu" signal "GND1")
		(10 "In4.Cu" signal "IN2")
		(12 "In5.Cu" signal "GND2")
		(14 "In6.Cu" signal "IN3")
		(16 "In7.Cu" signal "GND3")
		(18 "In8.Cu" signal "VCC")
		(20 "In9.Cu" signal "VCC1")
		(22 "In10.Cu" signal "GND4")
		(24 "In11.Cu" signal "IN4")
		(26 "In12.Cu" signal "GND5")
		(28 "In13.Cu" signal "IN5")
		(30 "In14.Cu" signal "GND6")
		(32 "In15.Cu" signal "IN6")
		(34 "In16.Cu" signal "GND7")
		(2 "B.Cu" signal "BOTTOM")
		(9 "F.Adhes" user "F.Adhesive")
		(11 "B.Adhes" user "B.Adhesive")
		(13 "F.Paste" user "Package Geometry/Pastemask Top")
		(15 "B.Paste" user "Package Geometry/Pastemask Bottom")
		(5 "F.SilkS" user "Ref Des/Silkscreen Top")
		(7 "B.SilkS" user "Ref Des/Silkscreen Bottom")
		(1 "F.Mask" user "Board Geometry/Soldermask Top")
		(3 "B.Mask" user "Board Geometry/Soldermask Bottom")
		(17 "Dwgs.User" user "User.Drawings")
		(19 "Cmts.User" user "User.Comments")
		(21 "Eco1.User" user "User.Eco1")
		(23 "Eco2.User" user "User.Eco2")
		(25 "Edge.Cuts" user "Board Geometry/Outline")
		(27 "Margin" user)
		(31 "F.CrtYd" user "Package Geometry/Place Bound Top")
		(29 "B.CrtYd" user "Package Geometry/Place Bound Bottom")
		(35 "F.Fab" user "Ref Des/Assembly Top")
		(33 "B.Fab" user "Ref Des/Assembly Bottom")
	)
	(footprint ""
		(layer "F.Cu")
		(at 100.151184 -35.30092)
		(property "Reference" "R3192"
			(at 0 0 0)
			(layer "F.SilkS")
			(hide yes)
			(effects
				(font
					(size 1.27 1.27)
				)
			)
		)
		(property "Value" ""
			(at 0 0 0)
			(layer "F.Fab")
			(effects
				(font
					(size 1.27 1.27)
				)
			)
		)
		(duplicate_pad_numbers_are_jumpers no)
		(fp_line
			(start -0.7874 -0.4064)
			(end 0.7874 -0.4064)
			(stroke
				(width 0.1524)
				(type default)
			)
			(layer "F.SilkS")
		)
		(fp_line
			(start -0.7874 0.4064)
			(end -0.7874 -0.4064)
			(stroke
				(width 0.1524)
				(type default)
			)
			(layer "F.SilkS")
		)
		(fp_line
			(start 0.7874 -0.4064)
			(end 0.7874 0.4064)
			(stroke
				(width 0.1524)
				(type default)
			)
			(layer "F.SilkS")
		)
		(fp_line
			(start 0.7874 0.4064)
			(end -0.7874 0.4064)
			(stroke
				(width 0.1524)
				(type default)
			)
			(layer "F.SilkS")
		)
		(fp_line
			(start -0.67945 -0.305054)
			(end -0.12065 -0.305054)
			(stroke
				(width 0.1)
				(type default)
			)
			(layer "F.Fab")
		)
		(fp_line
			(start -0.67945 0.3048)
			(end -0.67945 -0.305054)
			(stroke
				(width 0.1)
				(type default)
			)
			(layer "F.Fab")
		)
		(fp_line
			(start -0.12065 -0.305054)
			(end -0.12065 -0.2794)
			(stroke
				(width 0.1)
				(type default)
			)
			(layer "F.Fab")
		)
		(fp_line
			(start -0.12065 -0.2794)
			(end 0.12065 -0.2794)
			(stroke
				(width 0.1)
				(type default)
			)
			(layer "F.Fab")
		)
		(fp_line
			(start -0.12065 0.2794)
			(end -0.12065 0.3048)
			(stroke
				(width 0.1)
				(type default)
			)
			(layer "F.Fab")
		)
		(fp_line
			(start -0.12065 0.3048)
			(end -0.67945 0.3048)
			(stroke
				(width 0.1)
				(type default)
			)
			(layer "F.Fab")
		)
		(fp_line
			(start 0.120396 0.2794)
			(end -0.12065 0.2794)
			(stroke
				(width 0.1)
				(type default)
			)
			(layer "F.Fab")
		)
		(fp_line
			(start 0.120396 0.3048)
			(end 0.120396 0.2794)
			(stroke
				(width 0.1)
				(type default)
			)
			(layer "F.Fab")
		)
		(fp_line
			(start 0.12065 -0.3048)
			(end 0.67945 -0.3048)
			(stroke
				(width 0.1)
				(type default)
			)
			(layer "F.Fab")
		)
		(fp_line
			(start 0.12065 -0.2794)
			(end 0.12065 -0.3048)
			(stroke
				(width 0.1)
				(type default)
			)
			(layer "F.Fab")
		)
		(fp_line
			(start 0.67945 -0.3048)
			(end 0.67945 0.3048)
			(stroke
				(width 0.1)
				(type default)
			)
			(layer "F.Fab")
		)
		(fp_line
			(start 0.67945 0.3048)
			(end 0.120396 0.3048)
			(stroke
				(width 0.1)
				(type default)
			)
			(layer "F.Fab")
		)
		(pad "1" smd circle
			(at -0.40005 0)
			(size 0 0)
			(layers "F.Cu" "F.Mask" "F.Paste")
			(net "P3V3_AUX")
		)
		(pad "2" smd circle
			(at 0.40005 0)
			(size 0 0)
			(layers "F.Cu" "F.Mask" "F.Paste")
			(net "IRQ_LVC3_V3_2_WAKE_BUF_N")
		)
	)
	(footprint ""
		(layer "F.Cu")
		(at 394.067284 -390.1694)
		(property "Reference" "R1412"
			(at 0 0 0)
			(layer "F.SilkS")
			(hide yes)
			(effects
				(font
					(size 1.27 1.27)
				)
			)
		)
		(property "Value" ""
			(at 0 0 0)
			(layer "F.Fab")
			(effects
				(font
					(size 1.27 1.27)
				)
			)
		)
		(duplicate_pad_numbers_are_jumpers no)
		(fp_line
			(start -0.32512 -0.175006)
			(end 0.32512 -0.175006)
			(stroke
				(width 0.1)
				(type default)
			)
			(layer "F.Fab")
		)
		(fp_line
			(start -0.32512 0.175006)
			(end -0.32512 -0.175006)
			(stroke
				(width 0.1)
				(type default)
			)
			(layer "F.Fab")
		)
		(fp_line
			(start 0.32512 -0.175006)
			(end 0.32512 0.175006)
			(stroke
				(width 0.1)
				(type default)
			)
			(layer "F.Fab")
		)
		(fp_line
			(start 0.32512 0.175006)
			(end -0.32512 0.175006)
			(stroke
				(width 0.1)
				(type default)
			)
			(layer "F.Fab")
		)
		(pad "1" smd rect
			(at -0.2667 0)
			(size 0.3048 0.381)
			(layers "F.Cu" "F.Mask" "F.Paste")
			(net "CLKREQ_RT_CPU0_P3_N")
		)
		(pad "2" smd rect
			(at 0.2667 0 180)
			(size 0.3048 0.381)
			(layers "F.Cu" "F.Mask" "F.Paste")
			(net "GND")
		)
	)
	(footprint ""
		(layer "F.Cu")
		(at 206.4385 -402.191982 90)
		(property "Reference" "PC2181"
			(at 0 0 90)
			(layer "F.SilkS")
			(hide yes)
			(effects
				(font
					(size 1.27 1.27)
				)
			)
		)
		(property "Value" ""
			(at 0 0 90)
			(layer "F.Fab")
			(effects
				(font
					(size 1.27 1.27)
				)
			)
		)
		(duplicate_pad_numbers_are_jumpers no)
		(fp_line
			(start 0.7874 -0.4064)
			(end 0.7874 0.4064)
			(stroke
				(width 0.1524)
				(type default)
			)
			(layer "F.SilkS")
		)
		(fp_line
			(start -0.7874 -0.4064)
			(end 0.7874 -0.4064)
			(stroke
				(width 0.1524)
				(type default)
			)
			(layer "F.SilkS")
		)
		(fp_line
			(start 0.7874 0.4064)
			(end -0.7874 0.4064)
			(stroke
				(width 0.1524)
				(type default)
			)
			(layer "F.SilkS")
		)
		(fp_line
			(start -0.7874 0.4064)
			(end -0.7874 -0.4064)
			(stroke
				(width 0.1524)
				(type default)
			)
			(layer "F.SilkS")
		)
		(fp_line
			(start -0.12065 -0.305054)
			(end -0.12065 -0.2794)
			(stroke
				(width 0.1)
				(type default)
			)
			(layer "F.Fab")
		)
		(fp_line
			(start -0.67945 -0.305054)
			(end -0.12065 -0.305054)
			(stroke
				(width 0.1)
				(type default)
			)
			(layer "F.Fab")
		)
		(fp_line
			(start 0.67945 -0.3048)
			(end 0.67945 0.3048)
			(stroke
				(width 0.1)
				(type default)
			)
			(layer "F.Fab")
		)
		(fp_line
			(start 0.12065 -0.3048)
			(end 0.67945 -0.3048)
			(stroke
				(width 0.1)
				(type default)
			)
			(layer "F.Fab")
		)
		(fp_line
			(start 0.12065 -0.2794)
			(end 0.12065 -0.3048)
			(stroke
				(width 0.1)
				(type default)
			)
			(layer "F.Fab")
		)
		(fp_line
			(start -0.12065 -0.2794)
			(end 0.12065 -0.2794)
			(stroke
				(width 0.1)
				(type default)
			)
			(layer "F.Fab")
		)
		(fp_line
			(start 0.120396 0.2794)
			(end -0.12065 0.2794)
			(stroke
				(width 0.1)
				(type default)
			)
			(layer "F.Fab")
		)
		(fp_line
			(start -0.12065 0.2794)
			(end -0.12065 0.3048)
			(stroke
				(width 0.1)
				(type default)
			)
			(layer "F.Fab")
		)
		(fp_line
			(start 0.67945 0.3048)
			(end 0.120396 0.3048)
			(stroke
				(width 0.1)
				(type default)
			)
			(layer "F.Fab")
		)
		(fp_line
			(start 0.120396 0.3048)
			(end 0.120396 0.2794)
			(stroke
				(width 0.1)
				(type default)
			)
			(layer "F.Fab")
		)
		(fp_line
			(start -0.12065 0.3048)
			(end -0.67945 0.3048)
			(stroke
				(width 0.1)
				(type default)
			)
			(layer "F.Fab")
		)
		(fp_line
			(start -0.67945 0.3048)
			(end -0.67945 -0.305054)
			(stroke
				(width 0.1)
				(type default)
			)
			(layer "F.Fab")
		)
		(pad "1" smd circle
			(at -0.40005 0 90)
			(size 0 0)
			(layers "F.Cu" "F.Mask" "F.Paste")
			(net "HSC_VDD_R_2")
		)
		(pad "2" smd circle
			(at 0.40005 0 90)
			(size 0 0)
			(layers "F.Cu" "F.Mask" "F.Paste")
			(net "AGND_HSC")
		)
	)
)
